40 45 50
40 45 50
±10% ±10% ±10%
Single Single Single
Layer# Material Copper Weight (oz)
Thickness
(mil)
Tolerance
(mil) Glass Fabric Er Width Width Width Width Space Width Space Width Space Width Space Width Space Width Space Width Space
Soldermask 0.60 3.8
1 TOP 0.5+plating 1.95 6.7 5.2 4.2 3 4.5 6.3 6.3 5.8 7.6 5.1 7.6 4 4.5 4 14.7 3 4.5
EM-890 PP 2.30 ±0.709 1067x1 3.22
2 GND 0.5 (RG311(Rz<2.5um)) 0.65
EM-890 CORE 4.00 ±0.709 1078x1 3.23
3 IN1 1 (RG311(Rz<2.5um)) 1.30 7.1 5.7 4.6 3.5 4 7.2 5.4 6.3 5.6 5.6 5.5 4.5 3 4.5 9.6 3.75 3.5
EM-890 PP 5.00 ±0.984 1078x2 3.24
4 GND1 0.5 (RG311(Rz<2.5um)) 0.65
EM-890 CORE 4.00 ±0.709 1078x1 3.23
5 IN2 1 (RG311(Rz<2.5um)) 1.30 7.1 5.7 4.6 3.5 4 7.2 5.4 6.3 5.6 5.6 5.5 4.5 3 4.5 9.6 3.75 3.5
EM-890 PP 5.00 ±0.984 1078x2 3.24
6 GND2 0.5 (RG311(Rz<2.5um)) 0.65
EM-890 CORE 4.00 ±0.709 1078x1 3.23
7 IN3 1 (RG311(Rz<2.5um)) 1.30 7.1 5.7 4.6 3.5 4 7.2 5.4 6.3 5.6 5.6 5.5 4.5 3 4.5 9.6 3.75 3.5
EM-890 PP 5.00 ±0.984 1078x2 3.24
8 GND3 1 (RTF(Rz<4um)) 1.30
EM-370(Z) CORE 3.50 ±0.709 3313x1 3.85
9 VCC 2 (RTF) 2.60
EM-370(Z) PP 4.80 ±0.984 1080x2 3.87
10 VCC1 2 (RTF) 2.60
EM-370(Z) CORE 3.50 ±0.709 3313x1 3.85
11 GND4 1 (RTF(Rz<4um)) 1.30
EM-890 PP 5.00 ±0.984 1078x2 3.24
12 IN4 1 (RG311(Rz<2.5um)) 1.30 7.1 5.7 4.6 3.5 4 7.2 5.4 6.3 5.6 5.6 5.5 4.5 3 4.5 9.6 3.75 3.5
EM-890 CORE 4.00 ±0.709 1078x1 3.23
13 GND5 0.5 (RG311(Rz<2.5um)) 0.65
EM-890 PP 5.00 ±0.984 1078x2 3.24
14 IN5 1 (RG311(Rz<2.5um)) 1.30 7.1 5.7 4.6 3.5 4 7.2 5.4 6.3 5.6 5.6 5.5 4.5 3 4.5 9.6 3.75 3.5
EM-890 CORE 4.00 ±0.709 1078x1 3.23
15 GND6 0.5 (RG311(Rz<2.5um)) 0.65
EM-890 PP 5.00 ±0.984 1078x2 3.24
16 IN6 1 (RG311(Rz<2.5um)) 1.30 7.1 5.7 4.6 3.5 4 7.2 5.4 6.3 5.6 5.6 5.5 4.5 3 4.5 9.6 3.75 3.5
EM-890 CORE 4.00 ±0.709 1078x1 3.23
17 GND7 0.5 (RG311(Rz<2.5um)) 0.65
EM-890 PP 2.30 ±0.709 1067x1 3.22
18 BOTTOM 0.5+plating 1.95 6.7 5.2 4.2 3 4.5 6.3 6.3 5.8 7.6 5.1 7.6 4 4.5 4 14.7 3 4.5
Soldermask 0.60 3.8
Total 95.00 ±10%
Differential
Description
100
Z tolerance ±10% ±10% ±10%
Breakout
Single
85 (neck mode) 100
Differential Differential
BreakoutTarget Z (ohms) - StripLine 75 80 85 85 (neck mode)
±10% ±10%STACKUP
Target Z (ohms) - MicroStrip 75 80 85
Z Type Differential Differential Differential